# T6G (Grand Teton) — schematic netlist excerpt (pin names and nets, part order shuffled) for the footprints in the layout excerpt that follows; sources: Cadence DE-HDL packaged netlist, KiCad conversion of 04192023_DAF0TMB3IC0_F0TG_MB_C_brd_V02_OCP.brd

R6128  Q_RES  1K 1% CHIP  pkg 0402LF  page 84 : A = FM_BOARD_SKU_ID1 ; B = GND
R6020  Q_RES  2K 5% EMPTY  pkg 0402LF  page 151 : A = P3V3_AUX ; B = SGPIO_SCM_DO_<1>

(kicad_pcb
	(version 20260206)
	(generator "pcbnew")
	(generator_version "10.0")
	(general
		(thickness 1.6)
		(legacy_teardrops no)
	)
	(paper "A4")
	(title_block
		(title "04192023_DAF0TMB3IC0_F0TG_MB_C_brd_V02_OCP.brd")
		(comment 1 "Grand Teton / footprints 8064-8065 of 8354")
	)
	(layers
		(0 "F.Cu" signal "TOP")
		(4 "In1.Cu" signal "GND")
		(6 "In2.Cu" signal "IN1")
		(8 "In3.Cu" signal "GND1")
		(10 "In4.Cu" signal "IN2")
		(12 "In5.Cu" signal "GND2")
		(14 "In6.Cu" signal "IN3")
		(16 "In7.Cu" signal "GND3")
		(18 "In8.Cu" signal "VCC")
		(20 "In9.Cu" signal "VCC1")
		(22 "In10.Cu" signal "GND4")
		(24 "In11.Cu" signal "IN4")
		(26 "In12.Cu" signal "GND5")
		(28 "In13.Cu" signal "IN5")
		(30 "In14.Cu" signal "GND6")
		(32 "In15.Cu" signal "IN6")
		(34 "In16.Cu" signal "GND7")
		(2 "B.Cu" signal "BOTTOM")
		(9 "F.Adhes" user "F.Adhesive")
		(11 "B.Adhes" user "B.Adhesive")
		(13 "F.Paste" user "Package Geometry/Pastemask Top")
		(15 "B.Paste" user "Package Geometry/Pastemask Bottom")
		(5 "F.SilkS" user "Ref Des/Silkscreen Top")
		(7 "B.SilkS" user "Ref Des/Silkscreen Bottom")
		(1 "F.Mask" user "Board Geometry/Soldermask Top")
		(3 "B.Mask" user "Board Geometry/Soldermask Bottom")
		(17 "Dwgs.User" user "User.Drawings")
		(19 "Cmts.User" user "User.Comments")
		(21 "Eco1.User" user "User.Eco1")
		(23 "Eco2.User" user "User.Eco2")
		(25 "Edge.Cuts" user "Board Geometry/Outline")
		(27 "Margin" user)
		(31 "F.CrtYd" user "Package Geometry/Place Bound Top")
		(29 "B.CrtYd" user "Package Geometry/Place Bound Bottom")
		(35 "F.Fab" user "Ref Des/Assembly Top")
		(33 "B.Fab" user "Ref Des/Assembly Bottom")
	)
	(footprint ""
		(layer "B.Cu")
		(at 172.593 -100.294948 -90)
		(property "Reference" "R6020"
			(at 0 0 90)
			(layer "B.SilkS")
			(hide yes)
			(effects
				(font
					(size 1.27 1.27)
				)
				(justify mirror)
			)
		)
		(property "Value" ""
			(at 0 0 90)
			(layer "B.Fab")
			(effects
				(font
					(size 1.27 1.27)
				)
				(justify mirror)
			)
		)
		(duplicate_pad_numbers_are_jumpers no)
		(fp_line
			(start -0.7874 0.4064)
			(end 0.7874 0.4064)
			(stroke
				(width 0.1524)
				(type default)
			)
			(layer "B.SilkS")
		)
		(fp_line
			(start 0.7874 0.4064)
			(end 0.7874 -0.4064)
			(stroke
				(width 0.1524)
				(type default)
			)
			(layer "B.SilkS")
		)
		(fp_line
			(start -0.7874 -0.4064)
			(end -0.7874 0.4064)
			(stroke
				(width 0.1524)
				(type default)
			)
			(layer "B.SilkS")
		)
		(fp_line
			(start 0.7874 -0.4064)
			(end -0.7874 -0.4064)
			(stroke
				(width 0.1524)
				(type default)
			)
			(layer "B.SilkS")
		)
		(fp_line
			(start -0.67945 0.3048)
			(end -0.120396 0.3048)
			(stroke
				(width 0.1)
				(type default)
			)
			(layer "B.Fab")
		)
		(fp_line
			(start -0.120396 0.3048)
			(end -0.120396 0.2794)
			(stroke
				(width 0.1)
				(type default)
			)
			(layer "B.Fab")
		)
		(fp_line
			(start 0.12065 0.3048)
			(end 0.67945 0.3048)
			(stroke
				(width 0.1)
				(type default)
			)
			(layer "B.Fab")
		)
		(fp_line
			(start 0.67945 0.3048)
			(end 0.67945 -0.305054)
			(stroke
				(width 0.1)
				(type default)
			)
			(layer "B.Fab")
		)
		(fp_line
			(start -0.120396 0.2794)
			(end 0.12065 0.2794)
			(stroke
				(width 0.1)
				(type default)
			)
			(layer "B.Fab")
		)
		(fp_line
			(start 0.12065 0.2794)
			(end 0.12065 0.3048)
			(stroke
				(width 0.1)
				(type default)
			)
			(layer "B.Fab")
		)
		(fp_line
			(start -0.12065 -0.2794)
			(end -0.12065 -0.3048)
			(stroke
				(width 0.1)
				(type default)
			)
			(layer "B.Fab")
		)
		(fp_line
			(start 0.12065 -0.2794)
			(end -0.12065 -0.2794)
			(stroke
				(width 0.1)
				(type default)
			)
			(layer "B.Fab")
		)
		(fp_line
			(start -0.67945 -0.3048)
			(end -0.67945 0.3048)
			(stroke
				(width 0.1)
				(type default)
			)
			(layer "B.Fab")
		)
		(fp_line
			(start -0.12065 -0.3048)
			(end -0.67945 -0.3048)
			(stroke
				(width 0.1)
				(type default)
			)
			(layer "B.Fab")
		)
		(fp_line
			(start 0.12065 -0.305054)
			(end 0.12065 -0.2794)
			(stroke
				(width 0.1)
				(type default)
			)
			(layer "B.Fab")
		)
		(fp_line
			(start 0.67945 -0.305054)
			(end 0.12065 -0.305054)
			(stroke
				(width 0.1)
				(type default)
			)
			(layer "B.Fab")
		)
		(pad "1" smd circle
			(at 0.40005 0 90)
			(size 0 0)
			(layers "B.Cu" "B.Mask" "B.Paste")
			(net "P3V3_AUX")
		)
		(pad "2" smd circle
			(at -0.40005 0 90)
			(size 0 0)
			(layers "B.Cu" "B.Mask" "B.Paste")
			(net "SGPIO_SCM_DO_<1>")
		)
	)
	(footprint ""
		(layer "B.Cu")
		(at 402.186394 -354.439728 -90)
		(property "Reference" "R6128"
			(at 0 0 90)
			(layer "B.SilkS")
			(hide yes)
			(effects
				(font
					(size 1.27 1.27)
				)
				(justify mirror)
			)
		)
		(property "Value" ""
			(at 0 0 90)
			(layer "B.Fab")
			(effects
				(font
					(size 1.27 1.27)
				)
				(justify mirror)
			)
		)
		(duplicate_pad_numbers_are_jumpers no)
		(fp_line
			(start -0.7874 0.4064)
			(end 0.7874 0.4064)
			(stroke
				(width 0.1524)
				(type default)
			)
			(layer "B.SilkS")
		)
		(fp_line
			(start 0.7874 0.4064)
			(end 0.7874 -0.4064)
			(stroke
				(width 0.1524)
				(type default)
			)
			(layer "B.SilkS")
		)
		(fp_line
			(start -0.7874 -0.4064)
			(end -0.7874 0.4064)
			(stroke
				(width 0.1524)
				(type default)
			)
			(layer "B.SilkS")
		)
		(fp_line
			(start 0.7874 -0.4064)
			(end -0.7874 -0.4064)
			(stroke
				(width 0.1524)
				(type default)
			)
			(layer "B.SilkS")
		)
		(fp_line
			(start -0.67945 0.3048)
			(end -0.120396 0.3048)
			(stroke
				(width 0.1)
				(type default)
			)
			(layer "B.Fab")
		)
		(fp_line
			(start -0.120396 0.3048)
			(end -0.120396 0.2794)
			(stroke
				(width 0.1)
				(type default)
			)
			(layer "B.Fab")
		)
		(fp_line
			(start 0.12065 0.3048)
			(end 0.67945 0.3048)
			(stroke
				(width 0.1)
				(type default)
			)
			(layer "B.Fab")
		)
		(fp_line
			(start 0.67945 0.3048)
			(end 0.67945 -0.305054)
			(stroke
				(width 0.1)
				(type default)
			)
			(layer "B.Fab")
		)
		(fp_line
			(start -0.120396 0.2794)
			(end 0.12065 0.2794)
			(stroke
				(width 0.1)
				(type default)
			)
			(layer "B.Fab")
		)
		(fp_line
			(start 0.12065 0.2794)
			(end 0.12065 0.3048)
			(stroke
				(width 0.1)
				(type default)
			)
			(layer "B.Fab")
		)
		(fp_line
			(start -0.12065 -0.2794)
			(end -0.12065 -0.3048)
			(stroke
				(width 0.1)
				(type default)
			)
			(layer "B.Fab")
		)
		(fp_line
			(start 0.12065 -0.2794)
			(end -0.12065 -0.2794)
			(stroke
				(width 0.1)
				(type default)
			)
			(layer "B.Fab")
		)
		(fp_line
			(start -0.67945 -0.3048)
			(end -0.67945 0.3048)
			(stroke
				(width 0.1)
				(type default)
			)
			(layer "B.Fab")
		)
		(fp_line
			(start -0.12065 -0.3048)
			(end -0.67945 -0.3048)
			(stroke
				(width 0.1)
				(type default)
			)
			(layer "B.Fab")
		)
		(fp_line
			(start 0.12065 -0.305054)
			(end 0.12065 -0.2794)
			(stroke
				(width 0.1)
				(type default)
			)
			(layer "B.Fab")
		)
		(fp_line
			(start 0.67945 -0.305054)
			(end 0.12065 -0.305054)
			(stroke
				(width 0.1)
				(type default)
			)
			(layer "B.Fab")
		)
		(pad "1" smd circle
			(at 0.40005 0 90)
			(size 0 0)
			(layers "B.Cu" "B.Mask" "B.Paste")
			(net "FM_BOARD_SKU_ID1")
		)
		(pad "2" smd circle
			(at -0.40005 0 90)
			(size 0 0)
			(layers "B.Cu" "B.Mask" "B.Paste")
			(net "GND")
		)
	)
)
